# T6G (Grand Teton) — schematic netlist excerpt (pin names and nets, part order shuffled) for the footprints in the layout excerpt that follows; sources: Cadence DE-HDL packaged netlist, KiCad conversion of 04192023_DAF0TMB3IC0_F0TG_MB_C_brd_V02_OCP.brd

R8177  Q_RES  33 5% CHIP  pkg 0402LF  page 210 : A = PVDDCR_CPU0_P1_PMALERT ; B = PVDDCR_CPU0_P1_PMALERT_R
R1219  Q_RES  1K 1% CHIP  pkg 0201LF  page 186 : A = GND ; B = RT_ROM_MUX5_OE_N
R3924  Q_RES  0 5% CHIP  pkg 0402LF  page 262 : A = IRQ_SML1_PMBUS_ALERT_N ; B = IRQ_SML1_PMBUS_ALERT

(kicad_pcb
	(version 20260206)
	(generator "pcbnew")
	(generator_version "10.0")
	(general
		(thickness 1.6)
		(legacy_teardrops no)
	)
	(paper "A4")
	(title_block
		(title "04192023_DAF0TMB3IC0_F0TG_MB_C_brd_V02_OCP.brd")
		(comment 1 "Grand Teton / footprints 7785-7787 of 8354")
	)
	(layers
		(0 "F.Cu" signal "TOP")
		(4 "In1.Cu" signal "GND")
		(6 "In2.Cu" signal "IN1")
		(8 "In3.Cu" signal "GND1")
		(10 "In4.Cu" signal "IN2")
		(12 "In5.Cu" signal "GND2")
		(14 "In6.Cu" signal "IN3")
		(16 "In7.Cu" signal "GND3")
		(18 "In8.Cu" signal "VCC")
		(20 "In9.Cu" signal "VCC1")
		(22 "In10.Cu" signal "GND4")
		(24 "In11.Cu" signal "IN4")
		(26 "In12.Cu" signal "GND5")
		(28 "In13.Cu" signal "IN5")
		(30 "In14.Cu" signal "GND6")
		(32 "In15.Cu" signal "IN6")
		(34 "In16.Cu" signal "GND7")
		(2 "B.Cu" signal "BOTTOM")
		(9 "F.Adhes" user "F.Adhesive")
		(11 "B.Adhes" user "B.Adhesive")
		(13 "F.Paste" user "Package Geometry/Pastemask Top")
		(15 "B.Paste" user "Package Geometry/Pastemask Bottom")
		(5 "F.SilkS" user "Ref Des/Silkscreen Top")
		(7 "B.SilkS" user "Ref Des/Silkscreen Bottom")
		(1 "F.Mask" user "Board Geometry/Soldermask Top")
		(3 "B.Mask" user "Board Geometry/Soldermask Bottom")
		(17 "Dwgs.User" user "User.Drawings")
		(19 "Cmts.User" user "User.Comments")
		(21 "Eco1.User" user "User.Eco1")
		(23 "Eco2.User" user "User.Eco2")
		(25 "Edge.Cuts" user "Board Geometry/Outline")
		(27 "Margin" user)
		(31 "F.CrtYd" user "Package Geometry/Place Bound Top")
		(29 "B.CrtYd" user "Package Geometry/Place Bound Bottom")
		(35 "F.Fab" user "Ref Des/Assembly Top")
		(33 "B.Fab" user "Ref Des/Assembly Bottom")
	)
	(footprint ""
		(layer "B.Cu")
		(at 295.416986 -424.118786 180)
		(property "Reference" "R1219"
			(at 0 0 0)
			(layer "B.SilkS")
			(hide yes)
			(effects
				(font
					(size 1.27 1.27)
				)
				(justify mirror)
			)
		)
		(property "Value" ""
			(at 0 0 0)
			(layer "B.Fab")
			(effects
				(font
					(size 1.27 1.27)
				)
				(justify mirror)
			)
		)
		(duplicate_pad_numbers_are_jumpers no)
		(fp_line
			(start 0.32512 0.175006)
			(end 0.32512 -0.175006)
			(stroke
				(width 0.1)
				(type default)
			)
			(layer "B.Fab")
		)
		(fp_line
			(start 0.32512 -0.175006)
			(end -0.32512 -0.175006)
			(stroke
				(width 0.1)
				(type default)
			)
			(layer "B.Fab")
		)
		(fp_line
			(start -0.32512 0.175006)
			(end 0.32512 0.175006)
			(stroke
				(width 0.1)
				(type default)
			)
			(layer "B.Fab")
		)
		(fp_line
			(start -0.32512 -0.175006)
			(end -0.32512 0.175006)
			(stroke
				(width 0.1)
				(type default)
			)
			(layer "B.Fab")
		)
		(pad "1" smd rect
			(at 0.2667 0)
			(size 0.3048 0.381)
			(layers "B.Cu" "B.Mask" "B.Paste")
			(net "GND")
		)
		(pad "2" smd rect
			(at -0.2667 0 180)
			(size 0.3048 0.381)
			(layers "B.Cu" "B.Mask" "B.Paste")
			(net "RT_ROM_MUX5_OE_N")
		)
	)
	(footprint ""
		(layer "B.Cu")
		(at 183.3245 -404.051262 180)
		(property "Reference" "R3924"
			(at 0 0 0)
			(layer "B.SilkS")
			(hide yes)
			(effects
				(font
					(size 1.27 1.27)
				)
				(justify mirror)
			)
		)
		(property "Value" ""
			(at 0 0 0)
			(layer "B.Fab")
			(effects
				(font
					(size 1.27 1.27)
				)
				(justify mirror)
			)
		)
		(duplicate_pad_numbers_are_jumpers no)
		(fp_line
			(start 0.7874 0.4064)
			(end 0.7874 -0.4064)
			(stroke
				(width 0.1524)
				(type default)
			)
			(layer "B.SilkS")
		)
		(fp_line
			(start 0.7874 -0.4064)
			(end -0.7874 -0.4064)
			(stroke
				(width 0.1524)
				(type default)
			)
			(layer "B.SilkS")
		)
		(fp_line
			(start -0.7874 0.4064)
			(end 0.7874 0.4064)
			(stroke
				(width 0.1524)
				(type default)
			)
			(layer "B.SilkS")
		)
		(fp_line
			(start -0.7874 -0.4064)
			(end -0.7874 0.4064)
			(stroke
				(width 0.1524)
				(type default)
			)
			(layer "B.SilkS")
		)
		(fp_line
			(start 0.67945 0.3048)
			(end 0.67945 -0.305054)
			(stroke
				(width 0.1)
				(type default)
			)
			(layer "B.Fab")
		)
		(fp_line
			(start 0.67945 -0.305054)
			(end 0.12065 -0.305054)
			(stroke
				(width 0.1)
				(type default)
			)
			(layer "B.Fab")
		)
		(fp_line
			(start 0.12065 0.3048)
			(end 0.67945 0.3048)
			(stroke
				(width 0.1)
				(type default)
			)
			(layer "B.Fab")
		)
		(fp_line
			(start 0.12065 0.2794)
			(end 0.12065 0.3048)
			(stroke
				(width 0.1)
				(type default)
			)
			(layer "B.Fab")
		)
		(fp_line
			(start 0.12065 -0.2794)
			(end -0.12065 -0.2794)
			(stroke
				(width 0.1)
				(type default)
			)
			(layer "B.Fab")
		)
		(fp_line
			(start 0.12065 -0.305054)
			(end 0.12065 -0.2794)
			(stroke
				(width 0.1)
				(type default)
			)
			(layer "B.Fab")
		)
		(fp_line
			(start -0.120396 0.3048)
			(end -0.120396 0.2794)
			(stroke
				(width 0.1)
				(type default)
			)
			(layer "B.Fab")
		)
		(fp_line
			(start -0.120396 0.2794)
			(end 0.12065 0.2794)
			(stroke
				(width 0.1)
				(type default)
			)
			(layer "B.Fab")
		)
		(fp_line
			(start -0.12065 -0.2794)
			(end -0.12065 -0.3048)
			(stroke
				(width 0.1)
				(type default)
			)
			(layer "B.Fab")
		)
		(fp_line
			(start -0.12065 -0.3048)
			(end -0.67945 -0.3048)
			(stroke
				(width 0.1)
				(type default)
			)
			(layer "B.Fab")
		)
		(fp_line
			(start -0.67945 0.3048)
			(end -0.120396 0.3048)
			(stroke
				(width 0.1)
				(type default)
			)
			(layer "B.Fab")
		)
		(fp_line
			(start -0.67945 -0.3048)
			(end -0.67945 0.3048)
			(stroke
				(width 0.1)
				(type default)
			)
			(layer "B.Fab")
		)
		(pad "1" smd circle
			(at 0.40005 0)
			(size 0 0)
			(layers "B.Cu" "B.Mask" "B.Paste")
			(net "IRQ_SML1_PMBUS_ALERT_N")
		)
		(pad "2" smd circle
			(at -0.40005 0)
			(size 0 0)
			(layers "B.Cu" "B.Mask" "B.Paste")
			(net "IRQ_SML1_PMBUS_ALERT")
		)
	)
	(footprint ""
		(layer "B.Cu")
		(at 90.209878 -140.82141 180)
		(property "Reference" "R8177"
			(at 0 0 0)
			(layer "B.SilkS")
			(hide yes)
			(effects
				(font
					(size 1.27 1.27)
				)
				(justify mirror)
			)
		)
		(property "Value" ""
			(at 0 0 0)
			(layer "B.Fab")
			(effects
				(font
					(size 1.27 1.27)
				)
				(justify mirror)
			)
		)
		(duplicate_pad_numbers_are_jumpers no)
		(fp_line
			(start 0.7874 0.4064)
			(end 0.7874 -0.4064)
			(stroke
				(width 0.1524)
				(type default)
			)
			(layer "B.SilkS")
		)
		(fp_line
			(start 0.7874 -0.4064)
			(end -0.7874 -0.4064)
			(stroke
				(width 0.1524)
				(type default)
			)
			(layer "B.SilkS")
		)
		(fp_line
			(start -0.7874 0.4064)
			(end 0.7874 0.4064)
			(stroke
				(width 0.1524)
				(type default)
			)
			(layer "B.SilkS")
		)
		(fp_line
			(start -0.7874 -0.4064)
			(end -0.7874 0.4064)
			(stroke
				(width 0.1524)
				(type default)
			)
			(layer "B.SilkS")
		)
		(fp_line
			(start 0.67945 0.3048)
			(end 0.67945 -0.305054)
			(stroke
				(width 0.1)
				(type default)
			)
			(layer "B.Fab")
		)
		(fp_line
			(start 0.67945 -0.305054)
			(end 0.12065 -0.305054)
			(stroke
				(width 0.1)
				(type default)
			)
			(layer "B.Fab")
		)
		(fp_line
			(start 0.12065 0.3048)
			(end 0.67945 0.3048)
			(stroke
				(width 0.1)
				(type default)
			)
			(layer "B.Fab")
		)
		(fp_line
			(start 0.12065 0.2794)
			(end 0.12065 0.3048)
			(stroke
				(width 0.1)
				(type default)
			)
			(layer "B.Fab")
		)
		(fp_line
			(start 0.12065 -0.2794)
			(end -0.12065 -0.2794)
			(stroke
				(width 0.1)
				(type default)
			)
			(layer "B.Fab")
		)
		(fp_line
			(start 0.12065 -0.305054)
			(end 0.12065 -0.2794)
			(stroke
				(width 0.1)
				(type default)
			)
			(layer "B.Fab")
		)
		(fp_line
			(start -0.120396 0.3048)
			(end -0.120396 0.2794)
			(stroke
				(width 0.1)
				(type default)
			)
			(layer "B.Fab")
		)
		(fp_line
			(start -0.120396 0.2794)
			(end 0.12065 0.2794)
			(stroke
				(width 0.1)
				(type default)
			)
			(layer "B.Fab")
		)
		(fp_line
			(start -0.12065 -0.2794)
			(end -0.12065 -0.3048)
			(stroke
				(width 0.1)
				(type default)
			)
			(layer "B.Fab")
		)
		(fp_line
			(start -0.12065 -0.3048)
			(end -0.67945 -0.3048)
			(stroke
				(width 0.1)
				(type default)
			)
			(layer "B.Fab")
		)
		(fp_line
			(start -0.67945 0.3048)
			(end -0.120396 0.3048)
			(stroke
				(width 0.1)
				(type default)
			)
			(layer "B.Fab")
		)
		(fp_line
			(start -0.67945 -0.3048)
			(end -0.67945 0.3048)
			(stroke
				(width 0.1)
				(type default)
			)
			(layer "B.Fab")
		)
		(pad "1" smd circle
			(at 0.40005 0)
			(size 0 0)
			(layers "B.Cu" "B.Mask" "B.Paste")
			(net "PVDDCR_CPU0_P1_PMALERT")
		)
		(pad "2" smd circle
			(at -0.40005 0)
			(size 0 0)
			(layers "B.Cu" "B.Mask" "B.Paste")
			(net "PVDDCR_CPU0_P1_PMALERT_R")
		)
	)
)
